# T6G (Grand Teton) — schematic netlist excerpt (pin names and nets, part order shuffled) for the footprints in the layout excerpt that follows; sources: Cadence DE-HDL packaged netlist, KiCad conversion of 04192023_DAF0TMB3IC0_F0TG_MB_C_brd_V02_OCP.brd

C3904  Q_CAP  22UF 4V 20% X6S  pkg C0402  page 72 : A = PVDD11_S3_P1 ; B = GND
R654  Q_RES  4.7K 5% CHIP  pkg 0402LF  page 83 : A = SCM_USB_OC_N ; B = P1V8_AUX

(kicad_pcb
	(version 20260206)
	(generator "pcbnew")
	(generator_version "10.0")
	(general
		(thickness 1.6)
		(legacy_teardrops no)
	)
	(paper "A4")
	(title_block
		(title "04192023_DAF0TMB3IC0_F0TG_MB_C_brd_V02_OCP.brd")
		(comment 1 "Grand Teton / footprints 8218-8220 of 8354")
	)
	(layers
		(0 "F.Cu" signal "TOP")
		(4 "In1.Cu" signal "GND")
		(6 "In2.Cu" signal "IN1")
		(8 "In3.Cu" signal "GND1")
		(10 "In4.Cu" signal "IN2")
		(12 "In5.Cu" signal "GND2")
		(14 "In6.Cu" signal "IN3")
		(16 "In7.Cu" signal "GND3")
		(18 "In8.Cu" signal "VCC")
		(20 "In9.Cu" signal "VCC1")
		(22 "In10.Cu" signal "GND4")
		(24 "In11.Cu" signal "IN4")
		(26 "In12.Cu" signal "GND5")
		(28 "In13.Cu" signal "IN5")
		(30 "In14.Cu" signal "GND6")
		(32 "In15.Cu" signal "IN6")
		(34 "In16.Cu" signal "GND7")
		(2 "B.Cu" signal "BOTTOM")
		(9 "F.Adhes" user "F.Adhesive")
		(11 "B.Adhes" user "B.Adhesive")
		(13 "F.Paste" user "Package Geometry/Pastemask Top")
		(15 "B.Paste" user "Package Geometry/Pastemask Bottom")
		(5 "F.SilkS" user "Ref Des/Silkscreen Top")
		(7 "B.SilkS" user "Ref Des/Silkscreen Bottom")
		(1 "F.Mask" user "Board Geometry/Soldermask Top")
		(3 "B.Mask" user "Board Geometry/Soldermask Bottom")
		(17 "Dwgs.User" user "User.Drawings")
		(19 "Cmts.User" user "User.Comments")
		(21 "Eco1.User" user "User.Eco1")
		(23 "Eco2.User" user "User.Eco2")
		(25 "Edge.Cuts" user "Board Geometry/Outline")
		(27 "Margin" user)
		(31 "F.CrtYd" user "Package Geometry/Place Bound Top")
		(29 "B.CrtYd" user "Package Geometry/Place Bound Bottom")
		(35 "F.Fab" user "Ref Des/Assembly Top")
		(33 "B.Fab" user "Ref Des/Assembly Bottom")
	)
	(footprint ""
		(layer "B.Cu")
		(at 405.22017 -202.891136 -90)
		(property "Reference" "R654"
			(at 0 0 90)
			(layer "B.SilkS")
			(hide yes)
			(effects
				(font
					(size 1.27 1.27)
				)
				(justify mirror)
			)
		)
		(property "Value" ""
			(at 0 0 90)
			(layer "B.Fab")
			(effects
				(font
					(size 1.27 1.27)
				)
				(justify mirror)
			)
		)
		(duplicate_pad_numbers_are_jumpers no)
		(fp_line
			(start -0.7874 0.4064)
			(end 0.7874 0.4064)
			(stroke
				(width 0.1524)
				(type default)
			)
			(layer "B.SilkS")
		)
		(fp_line
			(start 0.7874 0.4064)
			(end 0.7874 -0.4064)
			(stroke
				(width 0.1524)
				(type default)
			)
			(layer "B.SilkS")
		)
		(fp_line
			(start -0.7874 -0.4064)
			(end -0.7874 0.4064)
			(stroke
				(width 0.1524)
				(type default)
			)
			(layer "B.SilkS")
		)
		(fp_line
			(start 0.7874 -0.4064)
			(end -0.7874 -0.4064)
			(stroke
				(width 0.1524)
				(type default)
			)
			(layer "B.SilkS")
		)
		(fp_line
			(start -0.67945 0.3048)
			(end -0.120396 0.3048)
			(stroke
				(width 0.1)
				(type default)
			)
			(layer "B.Fab")
		)
		(fp_line
			(start -0.120396 0.3048)
			(end -0.120396 0.2794)
			(stroke
				(width 0.1)
				(type default)
			)
			(layer "B.Fab")
		)
		(fp_line
			(start 0.12065 0.3048)
			(end 0.67945 0.3048)
			(stroke
				(width 0.1)
				(type default)
			)
			(layer "B.Fab")
		)
		(fp_line
			(start 0.67945 0.3048)
			(end 0.67945 -0.305054)
			(stroke
				(width 0.1)
				(type default)
			)
			(layer "B.Fab")
		)
		(fp_line
			(start -0.120396 0.2794)
			(end 0.12065 0.2794)
			(stroke
				(width 0.1)
				(type default)
			)
			(layer "B.Fab")
		)
		(fp_line
			(start 0.12065 0.2794)
			(end 0.12065 0.3048)
			(stroke
				(width 0.1)
				(type default)
			)
			(layer "B.Fab")
		)
		(fp_line
			(start -0.12065 -0.2794)
			(end -0.12065 -0.3048)
			(stroke
				(width 0.1)
				(type default)
			)
			(layer "B.Fab")
		)
		(fp_line
			(start 0.12065 -0.2794)
			(end -0.12065 -0.2794)
			(stroke
				(width 0.1)
				(type default)
			)
			(layer "B.Fab")
		)
		(fp_line
			(start -0.67945 -0.3048)
			(end -0.67945 0.3048)
			(stroke
				(width 0.1)
				(type default)
			)
			(layer "B.Fab")
		)
		(fp_line
			(start -0.12065 -0.3048)
			(end -0.67945 -0.3048)
			(stroke
				(width 0.1)
				(type default)
			)
			(layer "B.Fab")
		)
		(fp_line
			(start 0.12065 -0.305054)
			(end 0.12065 -0.2794)
			(stroke
				(width 0.1)
				(type default)
			)
			(layer "B.Fab")
		)
		(fp_line
			(start 0.67945 -0.305054)
			(end 0.12065 -0.305054)
			(stroke
				(width 0.1)
				(type default)
			)
			(layer "B.Fab")
		)
		(pad "1" smd circle
			(at 0.40005 0 90)
			(size 0 0)
			(layers "B.Cu" "B.Mask" "B.Paste")
			(net "SCM_USB_OC_N")
		)
		(pad "2" smd circle
			(at -0.40005 0 90)
			(size 0 0)
			(layers "B.Cu" "B.Mask" "B.Paste")
			(net "P1V8_AUX")
		)
	)
	(footprint ""
		(layer "B.Cu")
		(at 103.951786 -104.674924 180)
		(property "Reference" ""
			(at 0 0 0)
			(layer "B.SilkS")
			(hide yes)
			(effects
				(font
					(size 1.27 1.27)
				)
				(justify mirror)
			)
		)
		(property "Value" ""
			(at 0 0 0)
			(layer "B.Fab")
			(effects
				(font
					(size 1.27 1.27)
				)
				(justify mirror)
			)
		)
		(duplicate_pad_numbers_are_jumpers no)
		(pad "1" smd circle
			(at 0 0)
			(size 0.9906 0.9906)
			(layers "B.Cu" "B.Mask" "B.Paste")
			(net "Net_45")
		)
		(zone
			(layer "B.Cu")
			(hatch none 0.5)
			(connect_pads
				(clearance 0)
			)
			(min_thickness 0.25)
			(keepout
				(tracks not_allowed)
				(vias allowed)
				(pads allowed)
				(copperpour not_allowed)
				(footprints allowed)
			)
			(placement
				(enabled no)
				(sheetname "")
			)
			(fill
				(thermal_gap 0.5)
				(thermal_bridge_width 0.5)
				(island_removal_mode 0)
			)
			(polygon
				(pts
					(arc
						(start 105.577386 -104.674924)
						(mid 102.326186 -104.674924)
						(end 105.577386 -104.674924)
					)
				)
			)
		)
	)
	(footprint ""
		(layer "B.Cu")
		(at 112.054386 -263.846564)
		(property "Reference" "C3904"
			(at 0 0 0)
			(layer "B.SilkS")
			(hide yes)
			(effects
				(font
					(size 1.27 1.27)
				)
				(justify mirror)
			)
		)
		(property "Value" ""
			(at 0 0 0)
			(layer "B.Fab")
			(effects
				(font
					(size 1.27 1.27)
				)
				(justify mirror)
			)
		)
		(duplicate_pad_numbers_are_jumpers no)
		(fp_line
			(start -0.7874 -0.4064)
			(end -0.7874 0.4064)
			(stroke
				(width 0.1524)
				(type default)
			)
			(layer "B.SilkS")
		)
		(fp_line
			(start -0.7874 0.4064)
			(end 0.7874 0.4064)
			(stroke
				(width 0.1524)
				(type default)
			)
			(layer "B.SilkS")
		)
		(fp_line
			(start 0.7874 -0.4064)
			(end -0.7874 -0.4064)
			(stroke
				(width 0.1524)
				(type default)
			)
			(layer "B.SilkS")
		)
		(fp_line
			(start 0.7874 0.4064)
			(end 0.7874 -0.4064)
			(stroke
				(width 0.1524)
				(type default)
			)
			(layer "B.SilkS")
		)
		(fp_line
			(start -0.67945 -0.3048)
			(end -0.67945 0.3048)
			(stroke
				(width 0.1)
				(type default)
			)
			(layer "B.Fab")
		)
		(fp_line
			(start -0.67945 0.3048)
			(end -0.120396 0.3048)
			(stroke
				(width 0.1)
				(type default)
			)
			(layer "B.Fab")
		)
		(fp_line
			(start -0.12065 -0.3048)
			(end -0.67945 -0.3048)
			(stroke
				(width 0.1)
				(type default)
			)
			(layer "B.Fab")
		)
		(fp_line
			(start -0.12065 -0.2794)
			(end -0.12065 -0.3048)
			(stroke
				(width 0.1)
				(type default)
			)
			(layer "B.Fab")
		)
		(fp_line
			(start -0.120396 0.2794)
			(end 0.12065 0.2794)
			(stroke
				(width 0.1)
				(type default)
			)
			(layer "B.Fab")
		)
		(fp_line
			(start -0.120396 0.3048)
			(end -0.120396 0.2794)
			(stroke
				(width 0.1)
				(type default)
			)
			(layer "B.Fab")
		)
		(fp_line
			(start 0.12065 -0.305054)
			(end 0.12065 -0.2794)
			(stroke
				(width 0.1)
				(type default)
			)
			(layer "B.Fab")
		)
		(fp_line
			(start 0.12065 -0.2794)
			(end -0.12065 -0.2794)
			(stroke
				(width 0.1)
				(type default)
			)
			(layer "B.Fab")
		)
		(fp_line
			(start 0.12065 0.2794)
			(end 0.12065 0.3048)
			(stroke
				(width 0.1)
				(type default)
			)
			(layer "B.Fab")
		)
		(fp_line
			(start 0.12065 0.3048)
			(end 0.67945 0.3048)
			(stroke
				(width 0.1)
				(type default)
			)
			(layer "B.Fab")
		)
		(fp_line
			(start 0.67945 -0.305054)
			(end 0.12065 -0.305054)
			(stroke
				(width 0.1)
				(type default)
			)
			(layer "B.Fab")
		)
		(fp_line
			(start 0.67945 0.3048)
			(end 0.67945 -0.305054)
			(stroke
				(width 0.1)
				(type default)
			)
			(layer "B.Fab")
		)
		(pad "1" smd circle
			(at 0.40005 0 180)
			(size 0 0)
			(layers "B.Cu" "B.Mask" "B.Paste")
			(net "PVDD11_S3_P1")
		)
		(pad "2" smd circle
			(at -0.40005 0 180)
			(size 0 0)
			(layers "B.Cu" "B.Mask" "B.Paste")
			(net "GND")
		)
	)
)
